# T6G (Grand Teton) — schematic netlist excerpt (pin names and nets, part order shuffled) for the footprints in the layout excerpt that follows; sources: Cadence DE-HDL packaged netlist, KiCad conversion of 04192023_DAF0TMB3IC0_F0TG_MB_C_brd_V02_OCP.brd

R1303  Q_RES  1K 1% CHIP  pkg 0402LF  page 85 : A = FM_SMB_RST_E1S_0_N ; B = P3V3_AUX
C929  Q_CAP_DIFFBUS  DIFF BUS_0.22UF 6.3V 20% X6S  pkg C0201  page 63 : \1\ = P5E_CPU0_P0_TX_C_DP<2> ; \2\ = P5E_CPU0_P0_TX_DP<2>
R344  Q_RES  49.9 1% EMPTY  pkg 0201LF  page 180 : A = USB3_CPU0_BMC_TX_C2_DP ; B = GND

(kicad_pcb
	(version 20260206)
	(generator "pcbnew")
	(generator_version "10.0")
	(general
		(thickness 1.6)
		(legacy_teardrops no)
	)
	(paper "A4")
	(title_block
		(title "04192023_DAF0TMB3IC0_F0TG_MB_C_brd_V02_OCP.brd")
		(comment 1 "Grand Teton / footprints 3040-3042 of 8354")
	)
	(layers
		(0 "F.Cu" signal "TOP")
		(4 "In1.Cu" signal "GND")
		(6 "In2.Cu" signal "IN1")
		(8 "In3.Cu" signal "GND1")
		(10 "In4.Cu" signal "IN2")
		(12 "In5.Cu" signal "GND2")
		(14 "In6.Cu" signal "IN3")
		(16 "In7.Cu" signal "GND3")
		(18 "In8.Cu" signal "VCC")
		(20 "In9.Cu" signal "VCC1")
		(22 "In10.Cu" signal "GND4")
		(24 "In11.Cu" signal "IN4")
		(26 "In12.Cu" signal "GND5")
		(28 "In13.Cu" signal "IN5")
		(30 "In14.Cu" signal "GND6")
		(32 "In15.Cu" signal "IN6")
		(34 "In16.Cu" signal "GND7")
		(2 "B.Cu" signal "BOTTOM")
		(9 "F.Adhes" user "F.Adhesive")
		(11 "B.Adhes" user "B.Adhesive")
		(13 "F.Paste" user "Package Geometry/Pastemask Top")
		(15 "B.Paste" user "Package Geometry/Pastemask Bottom")
		(5 "F.SilkS" user "Ref Des/Silkscreen Top")
		(7 "B.SilkS" user "Ref Des/Silkscreen Bottom")
		(1 "F.Mask" user "Board Geometry/Soldermask Top")
		(3 "B.Mask" user "Board Geometry/Soldermask Bottom")
		(17 "Dwgs.User" user "User.Drawings")
		(19 "Cmts.User" user "User.Comments")
		(21 "Eco1.User" user "User.Eco1")
		(23 "Eco2.User" user "User.Eco2")
		(25 "Edge.Cuts" user "Board Geometry/Outline")
		(27 "Margin" user)
		(31 "F.CrtYd" user "Package Geometry/Place Bound Top")
		(29 "B.CrtYd" user "Package Geometry/Place Bound Bottom")
		(35 "F.Fab" user "Ref Des/Assembly Top")
		(33 "B.Fab" user "Ref Des/Assembly Bottom")
	)
	(footprint ""
		(layer "F.Cu")
		(at 298.989496 -381.41783 -90)
		(property "Reference" "C929"
			(at 0 0 270)
			(layer "F.SilkS")
			(hide yes)
			(effects
				(font
					(size 1.27 1.27)
				)
			)
		)
		(property "Value" ""
			(at 0 0 270)
			(layer "F.Fab")
			(effects
				(font
					(size 1.27 1.27)
				)
			)
		)
		(duplicate_pad_numbers_are_jumpers no)
		(fp_line
			(start -0.299974 0.150114)
			(end -0.299974 -0.150114)
			(stroke
				(width 0.1)
				(type default)
			)
			(layer "F.Fab")
		)
		(fp_line
			(start 0.299974 0.150114)
			(end -0.299974 0.150114)
			(stroke
				(width 0.1)
				(type default)
			)
			(layer "F.Fab")
		)
		(fp_line
			(start -0.299974 -0.150114)
			(end 0.299974 -0.150114)
			(stroke
				(width 0.1)
				(type default)
			)
			(layer "F.Fab")
		)
		(fp_line
			(start 0.299974 -0.150114)
			(end 0.299974 0.150114)
			(stroke
				(width 0.1)
				(type default)
			)
			(layer "F.Fab")
		)
		(pad "1" smd rect
			(at -0.2667 0 270)
			(size 0.3048 0.381)
			(layers "F.Cu" "F.Mask" "F.Paste")
			(net "P5E_CPU0_P0_TX_C_DP<2>")
		)
		(pad "2" smd rect
			(at 0.2667 0 270)
			(size 0.3048 0.381)
			(layers "F.Cu" "F.Mask" "F.Paste")
			(net "P5E_CPU0_P0_TX_DP<2>")
		)
	)
	(footprint ""
		(layer "F.Cu")
		(at 103.185722 -29.819854 90)
		(property "Reference" "R344"
			(at 0 0 90)
			(layer "F.SilkS")
			(hide yes)
			(effects
				(font
					(size 1.27 1.27)
				)
			)
		)
		(property "Value" ""
			(at 0 0 90)
			(layer "F.Fab")
			(effects
				(font
					(size 1.27 1.27)
				)
			)
		)
		(duplicate_pad_numbers_are_jumpers no)
		(fp_line
			(start 0.32512 -0.175006)
			(end 0.32512 0.175006)
			(stroke
				(width 0.1)
				(type default)
			)
			(layer "F.Fab")
		)
		(fp_line
			(start -0.32512 -0.175006)
			(end 0.32512 -0.175006)
			(stroke
				(width 0.1)
				(type default)
			)
			(layer "F.Fab")
		)
		(fp_line
			(start 0.32512 0.175006)
			(end -0.32512 0.175006)
			(stroke
				(width 0.1)
				(type default)
			)
			(layer "F.Fab")
		)
		(fp_line
			(start -0.32512 0.175006)
			(end -0.32512 -0.175006)
			(stroke
				(width 0.1)
				(type default)
			)
			(layer "F.Fab")
		)
		(pad "1" smd rect
			(at -0.2667 0 90)
			(size 0.3048 0.381)
			(layers "F.Cu" "F.Mask" "F.Paste")
			(net "USB3_CPU0_BMC_TX_C2_DP")
		)
		(pad "2" smd rect
			(at 0.2667 0 270)
			(size 0.3048 0.381)
			(layers "F.Cu" "F.Mask" "F.Paste")
			(net "GND")
		)
	)
	(footprint ""
		(layer "F.Cu")
		(at 188.849 -96.103948 -90)
		(property "Reference" "R1303"
			(at 0 0 270)
			(layer "F.SilkS")
			(hide yes)
			(effects
				(font
					(size 1.27 1.27)
				)
			)
		)
		(property "Value" ""
			(at 0 0 270)
			(layer "F.Fab")
			(effects
				(font
					(size 1.27 1.27)
				)
			)
		)
		(duplicate_pad_numbers_are_jumpers no)
		(fp_line
			(start -0.7874 0.4064)
			(end -0.7874 -0.4064)
			(stroke
				(width 0.1524)
				(type default)
			)
			(layer "F.SilkS")
		)
		(fp_line
			(start 0.7874 0.4064)
			(end -0.7874 0.4064)
			(stroke
				(width 0.1524)
				(type default)
			)
			(layer "F.SilkS")
		)
		(fp_line
			(start -0.7874 -0.4064)
			(end 0.7874 -0.4064)
			(stroke
				(width 0.1524)
				(type default)
			)
			(layer "F.SilkS")
		)
		(fp_line
			(start 0.7874 -0.4064)
			(end 0.7874 0.4064)
			(stroke
				(width 0.1524)
				(type default)
			)
			(layer "F.SilkS")
		)
		(fp_line
			(start -0.67945 0.3048)
			(end -0.67945 -0.305054)
			(stroke
				(width 0.1)
				(type default)
			)
			(layer "F.Fab")
		)
		(fp_line
			(start -0.12065 0.3048)
			(end -0.67945 0.3048)
			(stroke
				(width 0.1)
				(type default)
			)
			(layer "F.Fab")
		)
		(fp_line
			(start 0.120396 0.3048)
			(end 0.120396 0.2794)
			(stroke
				(width 0.1)
				(type default)
			)
			(layer "F.Fab")
		)
		(fp_line
			(start 0.67945 0.3048)
			(end 0.120396 0.3048)
			(stroke
				(width 0.1)
				(type default)
			)
			(layer "F.Fab")
		)
		(fp_line
			(start -0.12065 0.2794)
			(end -0.12065 0.3048)
			(stroke
				(width 0.1)
				(type default)
			)
			(layer "F.Fab")
		)
		(fp_line
			(start 0.120396 0.2794)
			(end -0.12065 0.2794)
			(stroke
				(width 0.1)
				(type default)
			)
			(layer "F.Fab")
		)
		(fp_line
			(start -0.12065 -0.2794)
			(end 0.12065 -0.2794)
			(stroke
				(width 0.1)
				(type default)
			)
			(layer "F.Fab")
		)
		(fp_line
			(start 0.12065 -0.2794)
			(end 0.12065 -0.3048)
			(stroke
				(width 0.1)
				(type default)
			)
			(layer "F.Fab")
		)
		(fp_line
			(start 0.12065 -0.3048)
			(end 0.67945 -0.3048)
			(stroke
				(width 0.1)
				(type default)
			)
			(layer "F.Fab")
		)
		(fp_line
			(start 0.67945 -0.3048)
			(end 0.67945 0.3048)
			(stroke
				(width 0.1)
				(type default)
			)
			(layer "F.Fab")
		)
		(fp_line
			(start -0.67945 -0.305054)
			(end -0.12065 -0.305054)
			(stroke
				(width 0.1)
				(type default)
			)
			(layer "F.Fab")
		)
		(fp_line
			(start -0.12065 -0.305054)
			(end -0.12065 -0.2794)
			(stroke
				(width 0.1)
				(type default)
			)
			(layer "F.Fab")
		)
		(pad "1" smd circle
			(at -0.40005 0 270)
			(size 0 0)
			(layers "F.Cu" "F.Mask" "F.Paste")
			(net "FM_SMB_RST_E1S_0_N")
		)
		(pad "2" smd circle
			(at 0.40005 0 270)
			(size 0 0)
			(layers "F.Cu" "F.Mask" "F.Paste")
			(net "P3V3_AUX")
		)
	)
)
